# T6G (Grand Teton) — schematic netlist excerpt (pin names and nets, part order shuffled) for the footprints in the layout excerpt that follows; sources: Cadence DE-HDL packaged netlist, KiCad conversion of 04192023_DAF0TMB3IC0_F0TG_MB_C_brd_V02_OCP.brd

PC593  Q_CAP  0.22UF 16V 10% X7R  pkg 0402  page 198 : A = SW_PVDDCR_SOC_P0_BOOT1_RC ; B = SW_PVDDCR_SOC_P0_PH1
R196  Q_RES  0 5% CHIP  pkg 0402LF  page 81 : A = CPU1_NV_SAVE_N ; B = FM_CPU1_NV_SAVE_N
C1560  Q_CAP_DIFFBUS  DIFF BUS_0.22UF 6.3V 20% X6S  pkg C0201  page 65 : \1\ = P5E_CPU0_G3_TX_C_DN<9> ; \2\ = P5E_CPU0_G3_TX_DN<9>

(kicad_pcb
	(version 20260206)
	(generator "pcbnew")
	(generator_version "10.0")
	(general
		(thickness 1.6)
		(legacy_teardrops no)
	)
	(paper "A4")
	(title_block
		(title "04192023_DAF0TMB3IC0_F0TG_MB_C_brd_V02_OCP.brd")
		(comment 1 "Grand Teton / footprints 107-109 of 8354")
	)
	(layers
		(0 "F.Cu" signal "TOP")
		(4 "In1.Cu" signal "GND")
		(6 "In2.Cu" signal "IN1")
		(8 "In3.Cu" signal "GND1")
		(10 "In4.Cu" signal "IN2")
		(12 "In5.Cu" signal "GND2")
		(14 "In6.Cu" signal "IN3")
		(16 "In7.Cu" signal "GND3")
		(18 "In8.Cu" signal "VCC")
		(20 "In9.Cu" signal "VCC1")
		(22 "In10.Cu" signal "GND4")
		(24 "In11.Cu" signal "IN4")
		(26 "In12.Cu" signal "GND5")
		(28 "In13.Cu" signal "IN5")
		(30 "In14.Cu" signal "GND6")
		(32 "In15.Cu" signal "IN6")
		(34 "In16.Cu" signal "GND7")
		(2 "B.Cu" signal "BOTTOM")
		(9 "F.Adhes" user "F.Adhesive")
		(11 "B.Adhes" user "B.Adhesive")
		(13 "F.Paste" user "Package Geometry/Pastemask Top")
		(15 "B.Paste" user "Package Geometry/Pastemask Bottom")
		(5 "F.SilkS" user "Ref Des/Silkscreen Top")
		(7 "B.SilkS" user "Ref Des/Silkscreen Bottom")
		(1 "F.Mask" user "Board Geometry/Soldermask Top")
		(3 "B.Mask" user "Board Geometry/Soldermask Bottom")
		(17 "Dwgs.User" user "User.Drawings")
		(19 "Cmts.User" user "User.Comments")
		(21 "Eco1.User" user "User.Eco1")
		(23 "Eco2.User" user "User.Eco2")
		(25 "Edge.Cuts" user "Board Geometry/Outline")
		(27 "Margin" user)
		(31 "F.CrtYd" user "Package Geometry/Place Bound Top")
		(29 "B.CrtYd" user "Package Geometry/Place Bound Bottom")
		(35 "F.Fab" user "Ref Des/Assembly Top")
		(33 "B.Fab" user "Ref Des/Assembly Bottom")
	)
	(footprint ""
		(layer "F.Cu")
		(at 183.650128 -133.55701 -90)
		(property "Reference" "R196"
			(at 0 0 270)
			(layer "F.SilkS")
			(hide yes)
			(effects
				(font
					(size 1.27 1.27)
				)
			)
		)
		(property "Value" ""
			(at 0 0 270)
			(layer "F.Fab")
			(effects
				(font
					(size 1.27 1.27)
				)
			)
		)
		(duplicate_pad_numbers_are_jumpers no)
		(fp_line
			(start -0.7874 0.4064)
			(end -0.7874 -0.4064)
			(stroke
				(width 0.1524)
				(type default)
			)
			(layer "F.SilkS")
		)
		(fp_line
			(start 0.7874 0.4064)
			(end -0.7874 0.4064)
			(stroke
				(width 0.1524)
				(type default)
			)
			(layer "F.SilkS")
		)
		(fp_line
			(start -0.7874 -0.4064)
			(end 0.7874 -0.4064)
			(stroke
				(width 0.1524)
				(type default)
			)
			(layer "F.SilkS")
		)
		(fp_line
			(start 0.7874 -0.4064)
			(end 0.7874 0.4064)
			(stroke
				(width 0.1524)
				(type default)
			)
			(layer "F.SilkS")
		)
		(fp_line
			(start -0.67945 0.3048)
			(end -0.67945 -0.305054)
			(stroke
				(width 0.1)
				(type default)
			)
			(layer "F.Fab")
		)
		(fp_line
			(start -0.12065 0.3048)
			(end -0.67945 0.3048)
			(stroke
				(width 0.1)
				(type default)
			)
			(layer "F.Fab")
		)
		(fp_line
			(start 0.120396 0.3048)
			(end 0.120396 0.2794)
			(stroke
				(width 0.1)
				(type default)
			)
			(layer "F.Fab")
		)
		(fp_line
			(start 0.67945 0.3048)
			(end 0.120396 0.3048)
			(stroke
				(width 0.1)
				(type default)
			)
			(layer "F.Fab")
		)
		(fp_line
			(start -0.12065 0.2794)
			(end -0.12065 0.3048)
			(stroke
				(width 0.1)
				(type default)
			)
			(layer "F.Fab")
		)
		(fp_line
			(start 0.120396 0.2794)
			(end -0.12065 0.2794)
			(stroke
				(width 0.1)
				(type default)
			)
			(layer "F.Fab")
		)
		(fp_line
			(start -0.12065 -0.2794)
			(end 0.12065 -0.2794)
			(stroke
				(width 0.1)
				(type default)
			)
			(layer "F.Fab")
		)
		(fp_line
			(start 0.12065 -0.2794)
			(end 0.12065 -0.3048)
			(stroke
				(width 0.1)
				(type default)
			)
			(layer "F.Fab")
		)
		(fp_line
			(start 0.12065 -0.3048)
			(end 0.67945 -0.3048)
			(stroke
				(width 0.1)
				(type default)
			)
			(layer "F.Fab")
		)
		(fp_line
			(start 0.67945 -0.3048)
			(end 0.67945 0.3048)
			(stroke
				(width 0.1)
				(type default)
			)
			(layer "F.Fab")
		)
		(fp_line
			(start -0.67945 -0.305054)
			(end -0.12065 -0.305054)
			(stroke
				(width 0.1)
				(type default)
			)
			(layer "F.Fab")
		)
		(fp_line
			(start -0.12065 -0.305054)
			(end -0.12065 -0.2794)
			(stroke
				(width 0.1)
				(type default)
			)
			(layer "F.Fab")
		)
		(pad "1" smd circle
			(at -0.40005 0 270)
			(size 0 0)
			(layers "F.Cu" "F.Mask" "F.Paste")
			(net "CPU1_NV_SAVE_N")
		)
		(pad "2" smd circle
			(at 0.40005 0 270)
			(size 0 0)
			(layers "F.Cu" "F.Mask" "F.Paste")
			(net "FM_CPU1_NV_SAVE_N")
		)
	)
	(footprint ""
		(layer "F.Cu")
		(at 396.038324 -172.51934 90)
		(property "Reference" "PC593"
			(at 0 0 90)
			(layer "F.SilkS")
			(hide yes)
			(effects
				(font
					(size 1.27 1.27)
				)
			)
		)
		(property "Value" ""
			(at 0 0 90)
			(layer "F.Fab")
			(effects
				(font
					(size 1.27 1.27)
				)
			)
		)
		(duplicate_pad_numbers_are_jumpers no)
		(fp_line
			(start 0.7874 -0.4064)
			(end 0.7874 0.4064)
			(stroke
				(width 0.1524)
				(type default)
			)
			(layer "F.SilkS")
		)
		(fp_line
			(start -0.7874 -0.4064)
			(end 0.7874 -0.4064)
			(stroke
				(width 0.1524)
				(type default)
			)
			(layer "F.SilkS")
		)
		(fp_line
			(start 0.7874 0.4064)
			(end -0.7874 0.4064)
			(stroke
				(width 0.1524)
				(type default)
			)
			(layer "F.SilkS")
		)
		(fp_line
			(start -0.7874 0.4064)
			(end -0.7874 -0.4064)
			(stroke
				(width 0.1524)
				(type default)
			)
			(layer "F.SilkS")
		)
		(fp_line
			(start -0.12065 -0.305054)
			(end -0.12065 -0.2794)
			(stroke
				(width 0.1)
				(type default)
			)
			(layer "F.Fab")
		)
		(fp_line
			(start -0.67945 -0.305054)
			(end -0.12065 -0.305054)
			(stroke
				(width 0.1)
				(type default)
			)
			(layer "F.Fab")
		)
		(fp_line
			(start 0.67945 -0.3048)
			(end 0.67945 0.3048)
			(stroke
				(width 0.1)
				(type default)
			)
			(layer "F.Fab")
		)
		(fp_line
			(start 0.12065 -0.3048)
			(end 0.67945 -0.3048)
			(stroke
				(width 0.1)
				(type default)
			)
			(layer "F.Fab")
		)
		(fp_line
			(start 0.12065 -0.2794)
			(end 0.12065 -0.3048)
			(stroke
				(width 0.1)
				(type default)
			)
			(layer "F.Fab")
		)
		(fp_line
			(start -0.12065 -0.2794)
			(end 0.12065 -0.2794)
			(stroke
				(width 0.1)
				(type default)
			)
			(layer "F.Fab")
		)
		(fp_line
			(start 0.120396 0.2794)
			(end -0.12065 0.2794)
			(stroke
				(width 0.1)
				(type default)
			)
			(layer "F.Fab")
		)
		(fp_line
			(start -0.12065 0.2794)
			(end -0.12065 0.3048)
			(stroke
				(width 0.1)
				(type default)
			)
			(layer "F.Fab")
		)
		(fp_line
			(start 0.67945 0.3048)
			(end 0.120396 0.3048)
			(stroke
				(width 0.1)
				(type default)
			)
			(layer "F.Fab")
		)
		(fp_line
			(start 0.120396 0.3048)
			(end 0.120396 0.2794)
			(stroke
				(width 0.1)
				(type default)
			)
			(layer "F.Fab")
		)
		(fp_line
			(start -0.12065 0.3048)
			(end -0.67945 0.3048)
			(stroke
				(width 0.1)
				(type default)
			)
			(layer "F.Fab")
		)
		(fp_line
			(start -0.67945 0.3048)
			(end -0.67945 -0.305054)
			(stroke
				(width 0.1)
				(type default)
			)
			(layer "F.Fab")
		)
		(pad "1" smd circle
			(at -0.40005 0 90)
			(size 0 0)
			(layers "F.Cu" "F.Mask" "F.Paste")
			(net "SW_PVDDCR_SOC_P0_BOOT1_RC")
		)
		(pad "2" smd circle
			(at 0.40005 0 90)
			(size 0 0)
			(layers "F.Cu" "F.Mask" "F.Paste")
			(net "SW_PVDDCR_SOC_P0_PH1")
		)
	)
	(footprint ""
		(layer "F.Cu")
		(at 406.771348 -16.100298 90)
		(property "Reference" "C1560"
			(at 0 0 90)
			(layer "F.SilkS")
			(hide yes)
			(effects
				(font
					(size 1.27 1.27)
				)
			)
		)
		(property "Value" ""
			(at 0 0 90)
			(layer "F.Fab")
			(effects
				(font
					(size 1.27 1.27)
				)
			)
		)
		(duplicate_pad_numbers_are_jumpers no)
		(fp_line
			(start 0.299974 -0.150114)
			(end 0.299974 0.150114)
			(stroke
				(width 0.1)
				(type default)
			)
			(layer "F.Fab")
		)
		(fp_line
			(start -0.299974 -0.150114)
			(end 0.299974 -0.150114)
			(stroke
				(width 0.1)
				(type default)
			)
			(layer "F.Fab")
		)
		(fp_line
			(start 0.299974 0.150114)
			(end -0.299974 0.150114)
			(stroke
				(width 0.1)
				(type default)
			)
			(layer "F.Fab")
		)
		(fp_line
			(start -0.299974 0.150114)
			(end -0.299974 -0.150114)
			(stroke
				(width 0.1)
				(type default)
			)
			(layer "F.Fab")
		)
		(pad "1" smd rect
			(at -0.2667 0 90)
			(size 0.3048 0.381)
			(layers "F.Cu" "F.Mask" "F.Paste")
			(net "P5E_CPU0_G3_TX_C_DN<9>")
		)
		(pad "2" smd rect
			(at 0.2667 0 90)
			(size 0.3048 0.381)
			(layers "F.Cu" "F.Mask" "F.Paste")
			(net "P5E_CPU0_G3_TX_DN<9>")
		)
	)
)
